(kicad_pcb
	(version 20260206)
	(generator "pcbnew")
	(generator_version "10.0")
	(general
		(thickness 1.6)
		(legacy_teardrops no)
	)
	(paper "A4")
	(title_block
		(title "v2-pdb — ms_pdb_v2.brd")
		(comment 1 "Open CloudServer (Microsoft) / footprints 277-280 of 348")
	)
	(layers
		(0 "F.Cu" signal "TOP")
		(4 "In1.Cu" signal "GND")
		(6 "In2.Cu" signal "IN1")
		(8 "In3.Cu" signal "VCC")
		(10 "In4.Cu" signal "VCC1")
		(12 "In5.Cu" signal "IN2")
		(14 "In6.Cu" signal "GND1")
		(2 "B.Cu" signal "BOTTOM")
		(9 "F.Adhes" user "F.Adhesive")
		(11 "B.Adhes" user "B.Adhesive")
		(13 "F.Paste" user "Package Geometry/Pastemask Top")
		(15 "B.Paste" user "Package Geometry/Pastemask Bottom")
		(5 "F.SilkS" user "Ref Des/Silkscreen Top")
		(7 "B.SilkS" user "Ref Des/Silkscreen Bottom")
		(1 "F.Mask" user "Board Geometry/Soldermask Top")
		(3 "B.Mask" user "Board Geometry/Soldermask Bottom")
		(17 "Dwgs.User" user "User.Drawings")
		(19 "Cmts.User" user "User.Comments")
		(21 "Eco1.User" user "User.Eco1")
		(23 "Eco2.User" user "User.Eco2")
		(25 "Edge.Cuts" user "Board Geometry/Outline")
		(27 "Margin" user)
		(31 "F.CrtYd" user "Package Geometry/Place Bound Top")
		(29 "B.CrtYd" user "Package Geometry/Place Bound Bottom")
		(35 "F.Fab" user "Ref Des/Assembly Top")
		(33 "B.Fab" user "Ref Des/Assembly Bottom")
	)
	(footprint ""
		(layer "F.Cu")
		(at 14.034516 -409.576016 -90)
		(property "Reference" "J28"
			(at -1.48209 -5.22351 90)
			(unlocked yes)
			(layer "F.SilkS")
			(effects
				(font
					(size 0.7874 0.5842)
					(thickness 0.1524)
				)
				(justify left)
			)
		)
		(property "Value" ""
			(at 0 0 270)
			(layer "F.Fab")
			(effects
				(font
					(size 1.27 1.27)
				)
			)
		)
		(duplicate_pad_numbers_are_jumpers no)
		(fp_line
			(start -3.754882 12.899898)
			(end -3.754882 3.7846)
			(stroke
				(width 0.1524)
				(type default)
			)
			(layer "F.SilkS")
		)
		(fp_line
			(start 12.644882 12.899898)
			(end -3.754882 12.899898)
			(stroke
				(width 0.1524)
				(type default)
			)
			(layer "F.SilkS")
		)
		(fp_line
			(start 12.644882 3.7846)
			(end 12.644882 12.899898)
			(stroke
				(width 0.1524)
				(type default)
			)
			(layer "F.SilkS")
		)
		(fp_line
			(start -3.754882 1.2192)
			(end -3.754882 -3.800094)
			(stroke
				(width 0.1524)
				(type default)
			)
			(layer "F.SilkS")
		)
		(fp_line
			(start -3.754882 -3.800094)
			(end 12.644882 -3.800094)
			(stroke
				(width 0.1524)
				(type default)
			)
			(layer "F.SilkS")
		)
		(fp_line
			(start 12.644882 -3.800094)
			(end 12.644882 1.2192)
			(stroke
				(width 0.1524)
				(type default)
			)
			(layer "F.SilkS")
		)
		(fp_poly
			(pts
				(xy -3.807714 -0.117094) (xy -4.479544 0.218948) (xy -4.479544 -0.453136)
			)
			(stroke
				(width 0)
				(type default)
			)
			(fill yes)
			(layer "F.SilkS")
		)
		(fp_poly
			(pts
				(xy -2.591562 11.176) (xy 1.370838 11.176) (xy 1.370838 9.7282) (xy -2.591562 9.7282)
			)
			(stroke
				(width 0)
				(type default)
			)
			(fill no)
			(layer "B.CrtYd")
		)
		(fp_poly
			(pts
				(xy 7.5184 11.176) (xy 11.4808 11.176) (xy 11.4808 9.7282) (xy 7.5184 9.7282)
			)
			(stroke
				(width 0)
				(type default)
			)
			(fill no)
			(layer "B.CrtYd")
		)
		(fp_poly
			(pts
				(xy 9.627362 -3.256026) (xy 9.627362 -1.808226) (xy 8.357362 -1.808226) (xy 8.357362 0.731774) (xy -0.735838 0.731774)
				(xy -0.735838 -0.741426) (xy 0.534162 -0.741426) (xy 0.534162 -3.256026)
			)
			(stroke
				(width 0)
				(type default)
			)
			(fill no)
			(layer "B.CrtYd")
		)
		(fp_poly
			(pts
				(arc
					(start -3.430016 1.268222)
					(mid -3.430016 3.732022)
					(end -3.430016 1.268222)
				)
			)
			(stroke
				(width 0)
				(type default)
			)
			(fill no)
			(layer "B.CrtYd")
		)
		(fp_poly
			(pts
				(arc
					(start 12.320016 1.267968)
					(mid 12.320016 3.732276)
					(end 12.320016 1.267968)
				)
			)
			(stroke
				(width 0)
				(type default)
			)
			(fill no)
			(layer "B.CrtYd")
		)
		(fp_poly
			(pts
				(arc
					(start -1.27 4.4958)
					(mid -1.27 8.2042)
					(end -1.27 4.4958)
				)
			)
			(stroke
				(width 0)
				(type default)
			)
			(fill no)
			(layer "B.CrtYd")
		)
		(fp_poly
			(pts
				(arc
					(start 10.16 4.4958)
					(mid 10.16 8.2042)
					(end 10.16 4.4958)
				)
			)
			(stroke
				(width 0)
				(type default)
			)
			(fill no)
			(layer "B.CrtYd")
		)
		(fp_poly
			(pts
				(xy -3.754882 12.899898)
				(arc
					(start -3.754882 3.688334)
					(mid -4.662083 2.499901)
					(end -3.754882 1.311656)
				)
				(xy -3.754882 -3.800094) (xy 12.644882 -3.800094)
				(arc
					(start 12.644882 1.311656)
					(mid 13.551838 2.499901)
					(end 12.644882 3.688334)
				)
				(xy 12.644882 12.899898)
			)
			(stroke
				(width 0)
				(type default)
			)
			(fill no)
			(layer "F.CrtYd")
		)
		(fp_line
			(start -3.754882 12.899898)
			(end -3.754882 -3.800094)
			(stroke
				(width 0.1)
				(type default)
			)
			(layer "F.Fab")
		)
		(fp_line
			(start 12.644882 12.899898)
			(end -3.754882 12.899898)
			(stroke
				(width 0.1)
				(type default)
			)
			(layer "F.Fab")
		)
		(fp_line
			(start -3.754882 -3.800094)
			(end 12.644882 -3.800094)
			(stroke
				(width 0.1)
				(type default)
			)
			(layer "F.Fab")
		)
		(fp_line
			(start 12.644882 -3.800094)
			(end 12.644882 12.899898)
			(stroke
				(width 0.1)
				(type default)
			)
			(layer "F.Fab")
		)
		(fp_poly
			(pts
				(xy -4.125214 0) (xy -5.806186 0.840486) (xy -5.806186 -0.840486)
			)
			(stroke
				(width 0)
				(type default)
			)
			(fill yes)
			(layer "F.Fab")
		)
		(fp_text user "7"
			(at 13.598398 -0.217932 0)
			(unlocked yes)
			(layer "F.SilkS")
			(effects
				(font
					(size 0.7874 0.5842)
					(thickness 0.1524)
				)
			)
		)
		(fp_text user "1"
			(at -4.614164 -0.854964 0)
			(unlocked yes)
			(layer "F.SilkS")
			(effects
				(font
					(size 0.7874 0.5842)
					(thickness 0.1524)
				)
			)
		)
		(fp_text user "8"
			(at 13.521944 -2.506726 0)
			(unlocked yes)
			(layer "F.SilkS")
			(effects
				(font
					(size 0.7874 0.5842)
					(thickness 0.1524)
				)
			)
		)
		(fp_text user "2"
			(at -4.563364 -2.729992 0)
			(unlocked yes)
			(layer "F.SilkS")
			(effects
				(font
					(size 0.7874 0.5842)
					(thickness 0.1524)
				)
			)
		)
		(fp_text user "1"
			(at -1.320038 0.081026 0)
			(unlocked yes)
			(layer "B.SilkS")
			(effects
				(font
					(size 0.7874 0.5842)
					(thickness 0.1524)
				)
				(justify mirror)
			)
		)
		(fp_text user "7"
			(at 9.437116 0.013462 0)
			(unlocked yes)
			(layer "B.SilkS")
			(effects
				(font
					(size 0.7874 0.5842)
					(thickness 0.1524)
				)
				(justify mirror)
			)
		)
		(fp_text user "2"
			(at -0.599694 -2.592832 0)
			(unlocked yes)
			(layer "B.SilkS")
			(effects
				(font
					(size 0.7874 0.5842)
					(thickness 0.1524)
				)
				(justify mirror)
			)
		)
		(fp_text user "8"
			(at 9.335008 -3.694938 0)
			(unlocked yes)
			(layer "B.SilkS")
			(effects
				(font
					(size 0.7874 0.5842)
					(thickness 0.1524)
				)
				(justify mirror)
			)
		)
		(fp_text user "7"
			(at 8.8646 0.085852 270)
			(unlocked yes)
			(layer "B.Fab")
			(effects
				(font
					(size 0.7874 0.5842)
					(thickness 0.000001)
				)
				(justify mirror)
			)
		)
		(fp_text user "1"
			(at -1.1811 -0.053848 270)
			(unlocked yes)
			(layer "B.Fab")
			(effects
				(font
					(size 0.7874 0.5842)
					(thickness 0.000001)
				)
				(justify mirror)
			)
		)
		(fp_text user "8"
			(at 10.1219 -2.479548 270)
			(unlocked yes)
			(layer "B.Fab")
			(effects
				(font
					(size 0.7874 0.5842)
					(thickness 0.000001)
				)
				(justify mirror)
			)
		)
		(fp_text user "2"
			(at -0.0635 -2.631948 270)
			(unlocked yes)
			(layer "B.Fab")
			(effects
				(font
					(size 0.7874 0.5842)
					(thickness 0.000001)
				)
				(justify mirror)
			)
		)
		(fp_text user "7"
			(at 13.2334 -0.079248 270)
			(unlocked yes)
			(layer "F.Fab")
			(effects
				(font
					(size 0.7874 0.5842)
					(thickness 0.000001)
				)
			)
		)
		(fp_text user "1"
			(at -4.4323 -1.019048 270)
			(unlocked yes)
			(layer "F.Fab")
			(effects
				(font
					(size 0.7874 0.5842)
					(thickness 0.000001)
				)
			)
		)
		(fp_text user "2"
			(at -4.4704 -2.581148 270)
			(unlocked yes)
			(layer "F.Fab")
			(effects
				(font
					(size 0.7874 0.5842)
					(thickness 0.000001)
				)
			)
		)
		(fp_text user "8"
			(at 13.2715 -2.593848 270)
			(unlocked yes)
			(layer "F.Fab")
			(effects
				(font
					(size 0.7874 0.5842)
					(thickness 0.000001)
				)
			)
		)
		(pad "" np_thru_hole circle
			(at -1.27 6.35 270)
			(size 3.2004 3.2004)
			(drill 3.2004)
			(layers "*.Cu" "*.Mask")
			(clearance 0.381)
			(thermal_gap 0.381)
		)
		(pad "" np_thru_hole circle
			(at 10.16 6.35 270)
			(size 3.2004 3.2004)
			(drill 3.2004)
			(layers "*.Cu" "*.Mask")
			(clearance 0.381)
			(thermal_gap 0.381)
		)
		(pad "1" thru_hole rect
			(at 0 0 270)
			(size 1.3208 1.3208)
			(drill 0.9144)
			(layers "*.Cu" "*.Mask")
			(remove_unused_layers no)
			(net "LAN2_P1_P")
			(clearance 0.0508)
			(thermal_gap 0.0508)
			(padstack
				(mode front_inner_back)
				(layer "Inner"
					(shape circle)
					(size 1.3208 1.3208)
					(clearance 0.0508)
				)
				(layer "B.Cu"
					(shape rect)
					(size 1.3208 1.3208)
					(clearance 0.0508)
				)
			)
		)
		(pad "2" thru_hole circle
			(at 1.27 -2.54 270)
			(size 1.3208 1.3208)
			(drill 0.9144)
			(layers "*.Cu" "*.Mask")
			(remove_unused_layers no)
			(net "LAN2_P1_N")
			(clearance 0.0508)
			(thermal_gap 0.0508)
		)
		(pad "3" thru_hole circle
			(at 2.54 0 270)
			(size 1.3208 1.3208)
			(drill 0.9144)
			(layers "*.Cu" "*.Mask")
			(remove_unused_layers no)
			(net "LAN2_P2_P")
			(clearance 0.0508)
			(thermal_gap 0.0508)
		)
		(pad "4" thru_hole circle
			(at 3.81 -2.54 270)
			(size 1.3208 1.3208)
			(drill 0.9144)
			(layers "*.Cu" "*.Mask")
			(remove_unused_layers no)
			(net "LAN2_P3_P")
			(clearance 0.0508)
			(thermal_gap 0.0508)
		)
		(pad "5" thru_hole circle
			(at 5.08 0 270)
			(size 1.3208 1.3208)
			(drill 0.9144)
			(layers "*.Cu" "*.Mask")
			(remove_unused_layers no)
			(net "LAN2_P3_N")
			(clearance 0.0508)
			(thermal_gap 0.0508)
		)
		(pad "6" thru_hole circle
			(at 6.35 -2.54 270)
			(size 1.3208 1.3208)
			(drill 0.9144)
			(layers "*.Cu" "*.Mask")
			(remove_unused_layers no)
			(net "LAN2_P2_N")
			(clearance 0.0508)
			(thermal_gap 0.0508)
		)
		(pad "7" thru_hole circle
			(at 7.62 0 270)
			(size 1.3208 1.3208)
			(drill 0.9144)
			(layers "*.Cu" "*.Mask")
			(remove_unused_layers no)
			(net "LAN2_P4_P")
			(clearance 0.0508)
			(thermal_gap 0.0508)
		)
		(pad "8" thru_hole circle
			(at 8.89 -2.54 270)
			(size 1.3208 1.3208)
			(drill 0.9144)
			(layers "*.Cu" "*.Mask")
			(remove_unused_layers no)
			(net "LAN2_P4_N")
			(clearance 0.0508)
			(thermal_gap 0.0508)
		)
		(pad "9" thru_hole circle
			(at -1.854962 10.459974 270)
			(size 1.3208 1.3208)
			(drill 0.9144)
			(layers "*.Cu" "*.Mask")
			(remove_unused_layers no)
			(net "N42132933")
			(clearance 0.0508)
			(thermal_gap 0.0508)
		)
		(pad "10" thru_hole circle
			(at 0.635 10.459974 270)
			(size 1.3208 1.3208)
			(drill 0.9144)
			(layers "*.Cu" "*.Mask")
			(remove_unused_layers no)
			(net "N42132545")
			(clearance 0.0508)
			(thermal_gap 0.0508)
		)
		(pad "11" thru_hole circle
			(at 8.255 10.459974 270)
			(size 1.3208 1.3208)
			(drill 0.9144)
			(layers "*.Cu" "*.Mask")
			(remove_unused_layers no)
			(net "Net_115")
			(clearance 0.0508)
			(thermal_gap 0.0508)
		)
		(pad "12" thru_hole circle
			(at 10.744962 10.459974 270)
			(size 1.3208 1.3208)
			(drill 0.9144)
			(layers "*.Cu" "*.Mask")
			(remove_unused_layers no)
			(net "N42132358")
			(clearance 0.0508)
			(thermal_gap 0.0508)
		)
		(pad "G1" thru_hole circle
			(at -3.430016 2.500122 270)
			(size 2.3622 2.3622)
			(drill 1.6002)
			(layers "*.Cu" "*.Mask")
			(remove_unused_layers no)
			(net "GND")
			(clearance -0.127)
		)
		(pad "G2" thru_hole circle
			(at 12.320016 2.500122 270)
			(size 2.3622 2.3622)
			(drill 1.6002)
			(layers "*.Cu" "*.Mask")
			(remove_unused_layers no)
			(net "GND")
			(clearance -0.127)
		)
		(zone
			(layers "F.Cu" "B.Cu" "In1.Cu" "In2.Cu" "In3.Cu" "In4.Cu" "In5.Cu" "In6.Cu")
			(hatch none 0.5)
			(connect_pads
				(clearance 0)
			)
			(min_thickness 0.25)
			(keepout
				(tracks not_allowed)
				(vias allowed)
				(pads allowed)
				(copperpour not_allowed)
				(footprints allowed)
			)
			(placement
				(enabled no)
				(sheetname "")
			)
			(fill
				(thermal_gap 0.5)
				(thermal_bridge_width 0.5)
				(island_removal_mode 0)
			)
			(polygon
				(pts
					(arc
						(start 9.691116 -410.846016)
						(mid 5.677916 -410.846016)
						(end 9.691116 -410.846016)
					)
				)
			)
		)
		(zone
			(layers "F.Cu" "B.Cu" "In1.Cu" "In2.Cu" "In3.Cu" "In4.Cu" "In5.Cu" "In6.Cu")
			(hatch none 0.5)
			(connect_pads
				(clearance 0)
			)
			(min_thickness 0.25)
			(keepout
				(tracks not_allowed)
				(vias allowed)
				(pads allowed)
				(copperpour not_allowed)
				(footprints allowed)
			)
			(placement
				(enabled no)
				(sheetname "")
			)
			(fill
				(thermal_gap 0.5)
				(thermal_bridge_width 0.5)
				(island_removal_mode 0)
			)
			(polygon
				(pts
					(arc
						(start 9.691116 -399.416016)
						(mid 5.677916 -399.416016)
						(end 9.691116 -399.416016)
					)
				)
			)
		)
	)
	(footprint ""
		(layer "F.Cu")
		(at 27.640026 -461.429862 90)
		(property "Reference" "R133"
			(at -3.59664 -1.369314 90)
			(unlocked yes)
			(layer "F.SilkS")
			(effects
				(font
					(size 0.7874 0.5842)
					(thickness 0.1524)
				)
				(justify left)
			)
		)
		(property "Value" ""
			(at 0 0 90)
			(layer "F.Fab")
			(effects
				(font
					(size 1.27 1.27)
				)
			)
		)
		(duplicate_pad_numbers_are_jumpers no)
		(fp_line
			(start 0.7874 -0.4064)
			(end 0.7874 0.4064)
			(stroke
				(width 0.1524)
				(type default)
			)
			(layer "F.SilkS")
		)
		(fp_line
			(start -0.7874 -0.4064)
			(end 0.7874 -0.4064)
			(stroke
				(width 0.1524)
				(type default)
			)
			(layer "F.SilkS")
		)
		(fp_line
			(start 0.7874 0.4064)
			(end -0.7874 0.4064)
			(stroke
				(width 0.1524)
				(type default)
			)
			(layer "F.SilkS")
		)
		(fp_line
			(start -0.7874 0.4064)
			(end -0.7874 -0.4064)
			(stroke
				(width 0.1524)
				(type default)
			)
			(layer "F.SilkS")
		)
		(fp_poly
			(pts
				(xy -0.508 0.2794) (xy -0.508 0.2286) (xy -0.635 0.2286) (xy -0.635 -0.254) (xy -0.5334 -0.254)
				(xy -0.5334 -0.2794) (xy 0.5334 -0.2794) (xy 0.5334 -0.254) (xy 0.635 -0.254) (xy 0.635 0.254) (xy 0.5334 0.254)
				(xy 0.5334 0.2794)
			)
			(stroke
				(width 0)
				(type default)
			)
			(fill no)
			(layer "F.CrtYd")
		)
		(pad "1" smd rect
			(at 0.40005 0 90)
			(size 0.4572 0.508)
			(layers "F.Cu" "F.Mask" "F.Paste")
			(net "PSU6_REMOTE_N")
		)
		(pad "2" smd rect
			(at -0.40005 0 90)
			(size 0.4572 0.508)
			(layers "F.Cu" "F.Mask" "F.Paste")
			(net "PSU6_REMOTE_R2_N")
		)
	)
	(footprint ""
		(layer "F.Cu")
		(at 39.653718 -283.096208 -90)
		(property "Reference" "R16"
			(at 0.95885 -2.95783 90)
			(unlocked yes)
			(layer "F.SilkS")
			(effects
				(font
					(size 0.7874 0.5842)
					(thickness 0.1524)
				)
				(justify left)
			)
		)
		(property "Value" ""
			(at 0 0 270)
			(layer "F.Fab")
			(effects
				(font
					(size 1.27 1.27)
				)
			)
		)
		(duplicate_pad_numbers_are_jumpers no)
		(fp_line
			(start -0.7874 0.4064)
			(end -0.7874 -0.4064)
			(stroke
				(width 0.1524)
				(type default)
			)
			(layer "F.SilkS")
		)
		(fp_line
			(start 0.7874 0.4064)
			(end -0.7874 0.4064)
			(stroke
				(width 0.1524)
				(type default)
			)
			(layer "F.SilkS")
		)
		(fp_line
			(start -0.7874 -0.4064)
			(end 0.7874 -0.4064)
			(stroke
				(width 0.1524)
				(type default)
			)
			(layer "F.SilkS")
		)
		(fp_line
			(start 0.7874 -0.4064)
			(end 0.7874 0.4064)
			(stroke
				(width 0.1524)
				(type default)
			)
			(layer "F.SilkS")
		)
		(fp_poly
			(pts
				(xy -0.508 0.2794) (xy -0.508 0.2286) (xy -0.635 0.2286) (xy -0.635 -0.254) (xy -0.5334 -0.254)
				(xy -0.5334 -0.2794) (xy 0.5334 -0.2794) (xy 0.5334 -0.254) (xy 0.635 -0.254) (xy 0.635 0.254) (xy 0.5334 0.254)
				(xy 0.5334 0.2794)
			)
			(stroke
				(width 0)
				(type default)
			)
			(fill no)
			(layer "F.CrtYd")
		)
		(pad "1" smd rect
			(at 0.40005 0 270)
			(size 0.4572 0.508)
			(layers "F.Cu" "F.Mask" "F.Paste")
			(net "PSU4_AD0")
		)
		(pad "2" smd rect
			(at -0.40005 0 270)
			(size 0.4572 0.508)
			(layers "F.Cu" "F.Mask" "F.Paste")
			(net "P12V_STBY")
		)
	)
	(footprint ""
		(layer "F.Cu")
		(at 71.518526 -109.07776 -90)
		(property "Reference" "C15"
			(at -3.25374 -0.008128 90)
			(unlocked yes)
			(layer "F.SilkS")
			(effects
				(font
					(size 0.7874 0.5842)
					(thickness 0.1524)
				)
			)
		)
		(property "Value" ""
			(at 0 0 270)
			(layer "F.Fab")
			(effects
				(font
					(size 1.27 1.27)
				)
			)
		)
		(duplicate_pad_numbers_are_jumpers no)
		(fp_line
			(start -1.2954 0.5842)
			(end -1.2954 -0.5842)
			(stroke
				(width 0.1524)
				(type default)
			)
			(layer "F.SilkS")
		)
		(fp_line
			(start 1.2954 0.5842)
			(end -1.2954 0.5842)
			(stroke
				(width 0.1524)
				(type default)
			)
			(layer "F.SilkS")
		)
		(fp_line
			(start -1.2954 -0.5842)
			(end 1.2954 -0.5842)
			(stroke
				(width 0.1524)
				(type default)
			)
			(layer "F.SilkS")
		)
		(fp_line
			(start 0 -0.5842)
			(end 0 0.5842)
			(stroke
				(width 0.1524)
				(type default)
			)
			(layer "F.SilkS")
		)
		(fp_line
			(start 1.2954 -0.5842)
			(end 1.2954 0.5842)
			(stroke
				(width 0.1524)
				(type default)
			)
			(layer "F.SilkS")
		)
		(fp_poly
			(pts
				(xy 0.8636 -0.4572) (xy 0.8636 -0.3556) (xy 1.143 -0.3556) (xy 1.143 0.3556) (xy 0.8636 0.3556)
				(xy 0.8636 0.4572) (xy -0.8636 0.4572) (xy -0.8636 0.3556) (xy -1.143 0.3556) (xy -1.143 -0.3556)
				(xy -0.8636 -0.3556) (xy -0.8636 -0.4572)
			)
			(stroke
				(width 0)
				(type default)
			)
			(fill no)
			(layer "F.CrtYd")
		)
		(fp_line
			(start -0.884936 0.504952)
			(end -0.884936 -0.504952)
			(stroke
				(width 0.1)
				(type default)
			)
			(layer "F.Fab")
		)
		(fp_line
			(start 0.884936 0.504952)
			(end -0.884936 0.504952)
			(stroke
				(width 0.1)
				(type default)
			)
			(layer "F.Fab")
		)
		(fp_line
			(start -0.884936 -0.504952)
			(end 0.884936 -0.504952)
			(stroke
				(width 0.1)
				(type default)
			)
			(layer "F.Fab")
		)
		(fp_line
			(start 0.884936 -0.504952)
			(end 0.884936 0.504952)
			(stroke
				(width 0.1)
				(type default)
			)
			(layer "F.Fab")
		)
		(pad "1" smd rect
			(at 0.7366 0)
			(size 0.7112 0.8128)
			(layers "F.Cu" "F.Mask" "F.Paste")
			(net "P12V")
		)
		(pad "2" smd rect
			(at -0.7366 0)
			(size 0.7112 0.8128)
			(layers "F.Cu" "F.Mask" "F.Paste")
			(net "GND")
		)
	)
)
